FILE_TYPE = MACRO_DRAWING;
SET COLOR_WIRE YELLOW;
SET COLOR_PROP ORANGE;
SET COLOR_DOT WHITE;
SET COLOR_ARC YELLOW;
SET COLOR_BODY GREEN;
SET COLOR_NOTE PURPLE;
SET PROP_DISPLAY VALUE;
SET PAGE_NUMBER P189;
FORCEADD QUANTA_TITLE_BLOCK_C..1
(0 0);
FORCEPROP 1 LAST CUSTOM_TXT_CDS <NAME_2>
J 0
(-3175 50);
FORCEPROP 1 LAST CUSTOM_TXT_CDS <NAME_1>
J 0
(-3175 175);
FORCEPROP 1 LAST CUSTOM_TXT_CDS <Q_NUMBER>
J 0
(-1403 103);
DISPLAY 1.212766 (-1403 103);
FORCEPROP 1 LAST CUSTOM_TXT_CDS <Q_PROJ>
J 0
(-2382 102);
DISPLAY 1.212766 (-2382 102);
FORCEPROP 1 LAST CUSTOM_TXT_CDS <Q_REV>
J 0
(-184 103);
DISPLAY 1.212766 (-184 103);
FORCEPROP 1 LAST CUSTOM_TXT_CDS <CON_LAST_MODIFIED>
J 0
(-1885 15);
DISPLAY 0.978723 (-1885 15);
FORCEPROP 1 LAST CUSTOM_TXT_CDS <CON_PAGE_NUM> OF <CON_TOTAL_PAGES>
J 0
(-446 18);
DISPLAY 0.978723 (-446 18);
FORCEPROP 1 LAST Q_DEPT BU9
J 1
(-3763 49);
DISPLAY 1.957447 (-3763 49);
PAINT GREEN (-3763 49);
FORCEPROP 1 LAST Q_TITLE Blank
J 0
(-9366 26);
DISPLAY 2.446809 (-9366 26);
PAINT GREEN (-9366 26);
FORCEPROP 0 LAST CDS_CON_LAST_MODIFIED Wed Jul 21 11:37:59 2021
J 0
(-1885 15);
DISPLAY INVISIBLE (-1885 15);
FORCEPROP 1 LAST CDS_LMAN_SYM_OUTLINE -9475,6775,100,-125
J 0
(0 0);
DISPLAY 0.468085 (0 0);
PAINT GREEN (0 0);
DISPLAY INVISIBLE (0 0);
FORCEPROP 2 LAST CDS_LIB pure_quanta
J 0
(0 0);
DISPLAY INVISIBLE (0 0);
FORCEPROP 2 LAST PAGE_BORDER TRUE
J 0
(-7890 5250);
DISPLAY 0.638298 (-7890 5250);
PAINT PINK (-7890 5250);
DISPLAY INVISIBLE (-7890 5250);
FORCEPROP 1 LAST COMMENT_BODY TRUE
J 0
(12 -13);
DISPLAY 0.978723 (12 -13);
PAINT GREEN (12 -13);
DISPLAY INVISIBLE (12 -13);
FORCEPROP 2 LAST CUSTOM_TXT_CDS <XR_PAGE_TITLE>
J 0
(-7890 5250);
DISPLAY 0.638298 (-7890 5250);
PAINT PINK (-7890 5250);
DISPLAY INVISIBLE (-7890 5250);
FORCEPROP 2 LAST CDS_XR_PAGE_TITLE CR-190 : @T6G_MB_LIB.T6G(SCH_1):PAGE190
J 0
(-7890 5250);
DISPLAY 0.638298 (-7890 5250);
PAINT PINK (-7890 5250);
DISPLAY INVISIBLE (-7890 5250);
QUIT
